# T6G (Grand Teton) — schematic netlist excerpt (pin names and nets, part order shuffled) for the footprints in the layout excerpt that follows; sources: Cadence DE-HDL packaged netlist, KiCad conversion of 04192023_DAF0TMB3IC0_F0TG_MB_C_brd_V02_OCP.brd

R3491  Q_RES  100K 1% EMPTY  pkg 0402LF  page 129 : A = GPU_FPGA_EROT_RECOV_N ; B = GND
PC215  Q_CAP  0.1UF 25V 10% X7R  pkg 0402  page 209 : A = PVDD18_S5_P0 ; B = GND

(kicad_pcb
	(version 20260206)
	(generator "pcbnew")
	(generator_version "10.0")
	(general
		(thickness 1.6)
		(legacy_teardrops no)
	)
	(paper "A4")
	(title_block
		(title "04192023_DAF0TMB3IC0_F0TG_MB_C_brd_V02_OCP.brd")
		(comment 1 "Grand Teton / footprints 1305-1306 of 8354")
	)
	(layers
		(0 "F.Cu" signal "TOP")
		(4 "In1.Cu" signal "GND")
		(6 "In2.Cu" signal "IN1")
		(8 "In3.Cu" signal "GND1")
		(10 "In4.Cu" signal "IN2")
		(12 "In5.Cu" signal "GND2")
		(14 "In6.Cu" signal "IN3")
		(16 "In7.Cu" signal "GND3")
		(18 "In8.Cu" signal "VCC")
		(20 "In9.Cu" signal "VCC1")
		(22 "In10.Cu" signal "GND4")
		(24 "In11.Cu" signal "IN4")
		(26 "In12.Cu" signal "GND5")
		(28 "In13.Cu" signal "IN5")
		(30 "In14.Cu" signal "GND6")
		(32 "In15.Cu" signal "IN6")
		(34 "In16.Cu" signal "GND7")
		(2 "B.Cu" signal "BOTTOM")
		(9 "F.Adhes" user "F.Adhesive")
		(11 "B.Adhes" user "B.Adhesive")
		(13 "F.Paste" user "Package Geometry/Pastemask Top")
		(15 "B.Paste" user "Package Geometry/Pastemask Bottom")
		(5 "F.SilkS" user "Ref Des/Silkscreen Top")
		(7 "B.SilkS" user "Ref Des/Silkscreen Bottom")
		(1 "F.Mask" user "Board Geometry/Soldermask Top")
		(3 "B.Mask" user "Board Geometry/Soldermask Bottom")
		(17 "Dwgs.User" user "User.Drawings")
		(19 "Cmts.User" user "User.Comments")
		(21 "Eco1.User" user "User.Eco1")
		(23 "Eco2.User" user "User.Eco2")
		(25 "Edge.Cuts" user "Board Geometry/Outline")
		(27 "Margin" user)
		(31 "F.CrtYd" user "Package Geometry/Place Bound Top")
		(29 "B.CrtYd" user "Package Geometry/Place Bound Bottom")
		(35 "F.Fab" user "Ref Des/Assembly Top")
		(33 "B.Fab" user "Ref Des/Assembly Bottom")
	)
	(footprint ""
		(layer "F.Cu")
		(at 329.917044 -151.14397 -90)
		(property "Reference" "PC215"
			(at 0 0 270)
			(layer "F.SilkS")
			(hide yes)
			(effects
				(font
					(size 1.27 1.27)
				)
			)
		)
		(property "Value" ""
			(at 0 0 270)
			(layer "F.Fab")
			(effects
				(font
					(size 1.27 1.27)
				)
			)
		)
		(duplicate_pad_numbers_are_jumpers no)
		(fp_line
			(start -0.7874 0.4064)
			(end -0.7874 -0.4064)
			(stroke
				(width 0.1524)
				(type default)
			)
			(layer "F.SilkS")
		)
		(fp_line
			(start 0.7874 0.4064)
			(end -0.7874 0.4064)
			(stroke
				(width 0.1524)
				(type default)
			)
			(layer "F.SilkS")
		)
		(fp_line
			(start -0.7874 -0.4064)
			(end 0.7874 -0.4064)
			(stroke
				(width 0.1524)
				(type default)
			)
			(layer "F.SilkS")
		)
		(fp_line
			(start 0.7874 -0.4064)
			(end 0.7874 0.4064)
			(stroke
				(width 0.1524)
				(type default)
			)
			(layer "F.SilkS")
		)
		(fp_line
			(start -0.67945 0.3048)
			(end -0.67945 -0.305054)
			(stroke
				(width 0.1)
				(type default)
			)
			(layer "F.Fab")
		)
		(fp_line
			(start -0.12065 0.3048)
			(end -0.67945 0.3048)
			(stroke
				(width 0.1)
				(type default)
			)
			(layer "F.Fab")
		)
		(fp_line
			(start 0.120396 0.3048)
			(end 0.120396 0.2794)
			(stroke
				(width 0.1)
				(type default)
			)
			(layer "F.Fab")
		)
		(fp_line
			(start 0.67945 0.3048)
			(end 0.120396 0.3048)
			(stroke
				(width 0.1)
				(type default)
			)
			(layer "F.Fab")
		)
		(fp_line
			(start -0.12065 0.2794)
			(end -0.12065 0.3048)
			(stroke
				(width 0.1)
				(type default)
			)
			(layer "F.Fab")
		)
		(fp_line
			(start 0.120396 0.2794)
			(end -0.12065 0.2794)
			(stroke
				(width 0.1)
				(type default)
			)
			(layer "F.Fab")
		)
		(fp_line
			(start -0.12065 -0.2794)
			(end 0.12065 -0.2794)
			(stroke
				(width 0.1)
				(type default)
			)
			(layer "F.Fab")
		)
		(fp_line
			(start 0.12065 -0.2794)
			(end 0.12065 -0.3048)
			(stroke
				(width 0.1)
				(type default)
			)
			(layer "F.Fab")
		)
		(fp_line
			(start 0.12065 -0.3048)
			(end 0.67945 -0.3048)
			(stroke
				(width 0.1)
				(type default)
			)
			(layer "F.Fab")
		)
		(fp_line
			(start 0.67945 -0.3048)
			(end 0.67945 0.3048)
			(stroke
				(width 0.1)
				(type default)
			)
			(layer "F.Fab")
		)
		(fp_line
			(start -0.67945 -0.305054)
			(end -0.12065 -0.305054)
			(stroke
				(width 0.1)
				(type default)
			)
			(layer "F.Fab")
		)
		(fp_line
			(start -0.12065 -0.305054)
			(end -0.12065 -0.2794)
			(stroke
				(width 0.1)
				(type default)
			)
			(layer "F.Fab")
		)
		(pad "1" smd circle
			(at -0.40005 0 270)
			(size 0 0)
			(layers "F.Cu" "F.Mask" "F.Paste")
			(net "PVDD18_S5_P0")
		)
		(pad "2" smd circle
			(at 0.40005 0 270)
			(size 0 0)
			(layers "F.Cu" "F.Mask" "F.Paste")
			(net "GND")
		)
	)
	(footprint ""
		(layer "F.Cu")
		(at 118.618 -440.309 180)
		(property "Reference" "R3491"
			(at 0 0 180)
			(layer "F.SilkS")
			(hide yes)
			(effects
				(font
					(size 1.27 1.27)
				)
			)
		)
		(property "Value" ""
			(at 0 0 180)
			(layer "F.Fab")
			(effects
				(font
					(size 1.27 1.27)
				)
			)
		)
		(duplicate_pad_numbers_are_jumpers no)
		(fp_line
			(start 0.7874 0.4064)
			(end -0.7874 0.4064)
			(stroke
				(width 0.1524)
				(type default)
			)
			(layer "F.SilkS")
		)
		(fp_line
			(start 0.7874 -0.4064)
			(end 0.7874 0.4064)
			(stroke
				(width 0.1524)
				(type default)
			)
			(layer "F.SilkS")
		)
		(fp_line
			(start -0.7874 0.4064)
			(end -0.7874 -0.4064)
			(stroke
				(width 0.1524)
				(type default)
			)
			(layer "F.SilkS")
		)
		(fp_line
			(start -0.7874 -0.4064)
			(end 0.7874 -0.4064)
			(stroke
				(width 0.1524)
				(type default)
			)
			(layer "F.SilkS")
		)
		(fp_line
			(start 0.67945 0.3048)
			(end 0.120396 0.3048)
			(stroke
				(width 0.1)
				(type default)
			)
			(layer "F.Fab")
		)
		(fp_line
			(start 0.67945 -0.3048)
			(end 0.67945 0.3048)
			(stroke
				(width 0.1)
				(type default)
			)
			(layer "F.Fab")
		)
		(fp_line
			(start 0.12065 -0.2794)
			(end 0.12065 -0.3048)
			(stroke
				(width 0.1)
				(type default)
			)
			(layer "F.Fab")
		)
		(fp_line
			(start 0.12065 -0.3048)
			(end 0.67945 -0.3048)
			(stroke
				(width 0.1)
				(type default)
			)
			(layer "F.Fab")
		)
		(fp_line
			(start 0.120396 0.3048)
			(end 0.120396 0.2794)
			(stroke
				(width 0.1)
				(type default)
			)
			(layer "F.Fab")
		)
		(fp_line
			(start 0.120396 0.2794)
			(end -0.12065 0.2794)
			(stroke
				(width 0.1)
				(type default)
			)
			(layer "F.Fab")
		)
		(fp_line
			(start -0.12065 0.3048)
			(end -0.67945 0.3048)
			(stroke
				(width 0.1)
				(type default)
			)
			(layer "F.Fab")
		)
		(fp_line
			(start -0.12065 0.2794)
			(end -0.12065 0.3048)
			(stroke
				(width 0.1)
				(type default)
			)
			(layer "F.Fab")
		)
		(fp_line
			(start -0.12065 -0.2794)
			(end 0.12065 -0.2794)
			(stroke
				(width 0.1)
				(type default)
			)
			(layer "F.Fab")
		)
		(fp_line
			(start -0.12065 -0.305054)
			(end -0.12065 -0.2794)
			(stroke
				(width 0.1)
				(type default)
			)
			(layer "F.Fab")
		)
		(fp_line
			(start -0.67945 0.3048)
			(end -0.67945 -0.305054)
			(stroke
				(width 0.1)
				(type default)
			)
			(layer "F.Fab")
		)
		(fp_line
			(start -0.67945 -0.305054)
			(end -0.12065 -0.305054)
			(stroke
				(width 0.1)
				(type default)
			)
			(layer "F.Fab")
		)
		(pad "1" smd circle
			(at -0.40005 0 180)
			(size 0 0)
			(layers "F.Cu" "F.Mask" "F.Paste")
			(net "GPU_FPGA_EROT_RECOV_N")
		)
		(pad "2" smd circle
			(at 0.40005 0 180)
			(size 0 0)
			(layers "F.Cu" "F.Mask" "F.Paste")
			(net "GND")
		)
	)
)
